(kicad_pcb
	(version 20241229)
	(generator "pcbnew")
	(generator_version "9.0")
	(general
		(thickness 1.711)
		(legacy_teardrops no)
	)
	(paper "A4")
	(title_block
		(title "Antmicro Baseboard for Jetson AGX Thor")
		(date "2026-02-18")
		(rev "1.1.0")
		(company "Antmicro Ltd")
		(comment 1 "www.antmicro.com")
		(comment 9 "footprints 360-364 of 1170")
	)
	(layers
		(0 "F.Cu" signal)
		(4 "In1.Cu" signal)
		(6 "In2.Cu" signal)
		(8 "In3.Cu" signal)
		(10 "In4.Cu" jumper)
		(12 "In5.Cu" signal)
		(14 "In6.Cu" signal)
		(16 "In7.Cu" signal)
		(18 "In8.Cu" signal)
		(2 "B.Cu" signal)
		(9 "F.Adhes" user "F.Adhesive")
		(11 "B.Adhes" user "B.Adhesive")
		(13 "F.Paste" user)
		(15 "B.Paste" user)
		(5 "F.SilkS" user "F.Silkscreen")
		(7 "B.SilkS" user "B.Silkscreen")
		(1 "F.Mask" user)
		(3 "B.Mask" user)
		(17 "Dwgs.User" user "User.Drawings")
		(19 "Cmts.User" user "User.Comments")
		(21 "Eco1.User" user "User.Eco1")
		(23 "Eco2.User" user "User.Eco2")
		(25 "Edge.Cuts" user)
		(27 "Margin" user)
		(31 "F.CrtYd" user "F.Courtyard")
		(29 "B.CrtYd" user "B.Courtyard")
		(35 "F.Fab" user)
		(33 "B.Fab" user)
	)
	(footprint "antmicro-footprints:C_0402_1005Metric"
		(layer "F.Cu")
		(at 208 76.2 90)
		(descr "Capacitor SMD 0402")
		(tags "capacitor SMD 0402")
		(property "Reference" "C146"
			(at 0.9 0.4 90)
			(layer "F.SilkS")
			(effects
				(font
					(size 0.7 0.7)
					(thickness 0.15)
				)
				(justify left bottom)
			)
		)
		(property "Value" "C_4u7_25V_0402"
			(at -1.022927 2.155213 90)
			(layer "F.Fab")
			(effects
				(font
					(size 0.7 0.7)
					(thickness 0.15)
				)
				(justify left bottom)
			)
		)
		(property "Datasheet" "https://www.murata.com/products/productdetail?partno=GRM155C61E475ME15%23"
			(at 0 0 90)
			(layer "F.Fab")
			(hide yes)
			(effects
				(font
					(size 1.27 1.27)
					(thickness 0.15)
				)
			)
		)
		(property "Description" "SMD Multilayer Ceramic Capacitor"
			(at 0 0 90)
			(layer "F.Fab")
			(hide yes)
			(effects
				(font
					(size 1.27 1.27)
					(thickness 0.15)
				)
			)
		)
		(property "Manufacturer" "Murata"
			(at 0 0 90)
			(unlocked yes)
			(layer "F.Fab")
			(hide yes)
			(effects
				(font
					(size 1 1)
					(thickness 0.15)
				)
			)
		)
		(property "MPN" "GRM155C61E475ME15J"
			(at 0 0 90)
			(unlocked yes)
			(layer "F.Fab")
			(hide yes)
			(effects
				(font
					(size 1 1)
					(thickness 0.15)
				)
			)
		)
		(property "Val" "4u7"
			(at 0 0 90)
			(unlocked yes)
			(layer "F.Fab")
			(hide yes)
			(effects
				(font
					(size 1 1)
					(thickness 0.15)
				)
			)
		)
		(property "License" "Apache-2.0"
			(at 0 0 90)
			(unlocked yes)
			(layer "F.Fab")
			(hide yes)
			(effects
				(font
					(size 1 1)
					(thickness 0.15)
				)
			)
		)
		(property "Author" "Antmicro"
			(at 0 0 90)
			(unlocked yes)
			(layer "F.Fab")
			(hide yes)
			(effects
				(font
					(size 1 1)
					(thickness 0.15)
				)
			)
		)
		(property "Voltage" "25V"
			(at 0 0 90)
			(unlocked yes)
			(layer "F.Fab")
			(hide yes)
			(effects
				(font
					(size 1 1)
					(thickness 0.15)
				)
			)
		)
		(property "Dielectric" "X5S"
			(at 0 0 90)
			(unlocked yes)
			(layer "F.Fab")
			(hide yes)
			(effects
				(font
					(size 1 1)
					(thickness 0.15)
				)
			)
		)
		(sheetname "/USB Debug, PD/")
		(sheetfile "usb_debug_pd.kicad_sch")
		(attr smd)
		(fp_rect
			(start -0.925 -0.47)
			(end 0.925 0.47)
			(stroke
				(width 0.05)
				(type default)
			)
			(fill no)
			(layer "F.CrtYd")
		)
		(fp_line
			(start 0.504 -0.25)
			(end 0.504 0.248)
			(stroke
				(width 0.15)
				(type solid)
			)
			(layer "F.Fab")
		)
		(fp_line
			(start -0.494 -0.25)
			(end 0.504 -0.25)
			(stroke
				(width 0.15)
				(type solid)
			)
			(layer "F.Fab")
		)
		(fp_line
			(start 0.504 0.248)
			(end -0.494 0.248)
			(stroke
				(width 0.15)
				(type solid)
			)
			(layer "F.Fab")
		)
		(fp_line
			(start -0.494 0.248)
			(end -0.494 -0.25)
			(stroke
				(width 0.15)
				(type solid)
			)
			(layer "F.Fab")
		)
		(fp_text user "Author: Antmicro"
			(at -0.939 3.399 90)
			(layer "F.Fab")
			(effects
				(font
					(size 0.7 0.7)
					(thickness 0.15)
				)
				(justify left bottom)
			)
		)
		(fp_text user "${REFERENCE}"
			(at -0.939 4.599 90)
			(layer "F.Fab")
			(effects
				(font
					(size 0.7 0.7)
					(thickness 0.15)
				)
				(justify left bottom)
			)
		)
		(fp_text user "License: Apache-2.0"
			(at -0.939 5.799 90)
			(layer "F.Fab")
			(effects
				(font
					(size 0.7 0.7)
					(thickness 0.15)
				)
				(justify left bottom)
			)
		)
		(pad "1" smd roundrect
			(at -0.48 0 90)
			(size 0.59 0.64)
			(layers "F.Cu" "F.Mask" "F.Paste")
			(roundrect_rratio 0.25)
			(net 525 "/Power/USBPD2_HV")
			(pintype "passive")
		)
		(pad "2" smd roundrect
			(at 0.48 0 90)
			(size 0.59 0.64)
			(layers "F.Cu" "F.Mask" "F.Paste")
			(roundrect_rratio 0.25)
			(net 1 "GND")
			(pintype "passive")
		)
	)
	(footprint "antmicro-footprints:C_0402_1005Metric"
		(layer "F.Cu")
		(at 204.75 90.970856 180)
		(descr "Capacitor SMD 0402")
		(tags "capacitor SMD 0402")
		(property "Reference" "C319"
			(at 5.25 -0.429144 180)
			(layer "F.SilkS")
			(effects
				(font
					(size 0.7 0.7)
					(thickness 0.15)
				)
				(justify left bottom)
			)
		)
		(property "Value" "C_100n_0402"
			(at -1.022927 2.155213 180)
			(layer "F.Fab")
			(effects
				(font
					(size 0.7 0.7)
					(thickness 0.15)
				)
				(justify left bottom)
			)
		)
		(property "Datasheet" "https://www.murata.com/products/productdetail?partno=GRM155R61H104KE14%23"
			(at 0 0 180)
			(layer "F.Fab")
			(hide yes)
			(effects
				(font
					(size 1.27 1.27)
					(thickness 0.15)
				)
			)
		)
		(property "Description" "SMD Multilayer Ceramic Capacitor, 0.1 µF, 50 V, 0402 [1005 Metric], ± 10%, X5R, GRM Series"
			(at 0 0 180)
			(layer "F.Fab")
			(hide yes)
			(effects
				(font
					(size 1.27 1.27)
					(thickness 0.15)
				)
			)
		)
		(property "Manufacturer" "Murata"
			(at 0 0 180)
			(unlocked yes)
			(layer "F.Fab")
			(hide yes)
			(effects
				(font
					(size 1 1)
					(thickness 0.15)
				)
			)
		)
		(property "MPN" "GRM155R61H104KE14D"
			(at 0 0 180)
			(unlocked yes)
			(layer "F.Fab")
			(hide yes)
			(effects
				(font
					(size 1 1)
					(thickness 0.15)
				)
			)
		)
		(property "Val" "100n"
			(at 0 0 180)
			(unlocked yes)
			(layer "F.Fab")
			(hide yes)
			(effects
				(font
					(size 1 1)
					(thickness 0.15)
				)
			)
		)
		(property "License" "Apache-2.0"
			(at 0 0 180)
			(unlocked yes)
			(layer "F.Fab")
			(hide yes)
			(effects
				(font
					(size 1 1)
					(thickness 0.15)
				)
			)
		)
		(property "Author" "Antmicro"
			(at 0 0 180)
			(unlocked yes)
			(layer "F.Fab")
			(hide yes)
			(effects
				(font
					(size 1 1)
					(thickness 0.15)
				)
			)
		)
		(property "Voltage" "50V"
			(at 0 0 180)
			(unlocked yes)
			(layer "F.Fab")
			(hide yes)
			(effects
				(font
					(size 1 1)
					(thickness 0.15)
				)
			)
		)
		(property "Dielectric" "X5R"
			(at 0 0 180)
			(unlocked yes)
			(layer "F.Fab")
			(hide yes)
			(effects
				(font
					(size 1 1)
					(thickness 0.15)
				)
			)
		)
		(sheetname "/SoM_IO2/")
		(sheetfile "som_io2.kicad_sch")
		(attr smd)
		(fp_rect
			(start -0.925 -0.47)
			(end 0.925 0.47)
			(stroke
				(width 0.05)
				(type default)
			)
			(fill no)
			(layer "F.CrtYd")
		)
		(fp_line
			(start 0.504 0.248)
			(end -0.494 0.248)
			(stroke
				(width 0.15)
				(type solid)
			)
			(layer "F.Fab")
		)
		(fp_line
			(start 0.504 -0.25)
			(end 0.504 0.248)
			(stroke
				(width 0.15)
				(type solid)
			)
			(layer "F.Fab")
		)
		(fp_line
			(start -0.494 0.248)
			(end -0.494 -0.25)
			(stroke
				(width 0.15)
				(type solid)
			)
			(layer "F.Fab")
		)
		(fp_line
			(start -0.494 -0.25)
			(end 0.504 -0.25)
			(stroke
				(width 0.15)
				(type solid)
			)
			(layer "F.Fab")
		)
		(fp_text user "Author: Antmicro"
			(at -0.939 3.399 180)
			(layer "F.Fab")
			(effects
				(font
					(size 0.7 0.7)
					(thickness 0.15)
				)
				(justify left bottom)
			)
		)
		(fp_text user "${REFERENCE}"
			(at -0.939 4.599 180)
			(layer "F.Fab")
			(effects
				(font
					(size 0.7 0.7)
					(thickness 0.15)
				)
				(justify left bottom)
			)
		)
		(fp_text user "License: Apache-2.0"
			(at -0.939 5.799 180)
			(layer "F.Fab")
			(effects
				(font
					(size 0.7 0.7)
					(thickness 0.15)
				)
				(justify left bottom)
			)
		)
		(pad "1" smd roundrect
			(at -0.48 0 180)
			(size 0.59 0.64)
			(layers "F.Cu" "F.Mask" "F.Paste")
			(roundrect_rratio 0.25)
			(net 666 "/SoM_IO2/DP0.TX2-")
			(pintype "passive")
		)
		(pad "2" smd roundrect
			(at 0.48 0 180)
			(size 0.59 0.64)
			(layers "F.Cu" "F.Mask" "F.Paste")
			(roundrect_rratio 0.25)
			(net 617 "/SoM_IO2/DP0.TX2_C-")
			(pintype "passive")
		)
	)
	(footprint "antmicro-footprints:SW_KMR211NGLFS_SMD"
		(layer "F.Cu")
		(at 207 55.52 180)
		(property "Reference" "S6"
			(at 2 -2.1 180)
			(layer "F.SilkS")
			(hide yes)
			(effects
				(font
					(size 0.7 0.7)
					(thickness 0.15)
				)
				(justify right top)
			)
		)
		(property "Value" "SW_KMR211NGLFS_SMD"
			(at 0 2.8 0)
			(layer "F.Fab")
			(effects
				(font
					(size 0.7 0.7)
					(thickness 0.15)
				)
				(justify right top)
			)
		)
		(property "Datasheet" "http://www.farnell.com/datasheets/2631211.pdf"
			(at 0 0 0)
			(layer "F.Fab")
			(hide yes)
			(effects
				(font
					(size 1.27 1.27)
					(thickness 0.15)
				)
			)
		)
		(property "Description" "Tactile Switch, KMR 2 Series, Top Actuated, Surface Mount, Oval Button, 120 gf, 50mA at 32VDC"
			(at 0 0 0)
			(layer "F.Fab")
			(hide yes)
			(effects
				(font
					(size 1.27 1.27)
					(thickness 0.15)
				)
			)
		)
		(property "MPN" "KMR211NGLFS"
			(at 0 0 180)
			(unlocked yes)
			(layer "F.Fab")
			(hide yes)
			(effects
				(font
					(size 1 1)
					(thickness 0.15)
				)
			)
		)
		(property "Manufacturer" "C&K"
			(at 0 0 180)
			(unlocked yes)
			(layer "F.Fab")
			(hide yes)
			(effects
				(font
					(size 1 1)
					(thickness 0.15)
				)
			)
		)
		(property "Author" "Antmicro"
			(at 0 0 180)
			(unlocked yes)
			(layer "F.Fab")
			(hide yes)
			(effects
				(font
					(size 1 1)
					(thickness 0.15)
				)
			)
		)
		(property "License" "Apache-2.0"
			(at 0 0 180)
			(unlocked yes)
			(layer "F.Fab")
			(hide yes)
			(effects
				(font
					(size 1 1)
					(thickness 0.15)
				)
			)
		)
		(sheetname "/SoM_Power/")
		(sheetfile "som_power.kicad_sch")
		(attr smd)
		(fp_line
			(start 2.101 1.601)
			(end 2.101 1.48)
			(stroke
				(width 0.15)
				(type solid)
			)
			(layer "F.SilkS")
		)
		(fp_line
			(start 2.101 1.601)
			(end -2.1 1.601)
			(stroke
				(width 0.15)
				(type solid)
			)
			(layer "F.SilkS")
		)
		(fp_line
			(start 2.101 -1.58)
			(end 2.101 -1.459)
			(stroke
				(width 0.15)
				(type solid)
			)
			(layer "F.SilkS")
		)
		(fp_line
			(start 2.101 -1.6)
			(end -2.1 -1.6)
			(stroke
				(width 0.15)
				(type solid)
			)
			(layer "F.SilkS")
		)
		(fp_line
			(start -2.1 1.601)
			(end -2.1 1.48)
			(stroke
				(width 0.15)
				(type solid)
			)
			(layer "F.SilkS")
		)
		(fp_line
			(start -2.1 -1.6)
			(end -2.1 -1.499)
			(stroke
				(width 0.15)
				(type solid)
			)
			(layer "F.SilkS")
		)
		(fp_poly
			(pts
				(xy 2.751 1.75) (xy 2.751 -1.749) (xy -2.748 -1.749) (xy -2.748 1.749999)
			)
			(stroke
				(width 0.05)
				(type solid)
			)
			(fill no)
			(layer "F.CrtYd")
		)
		(fp_line
			(start 2.101 1.601)
			(end 2.101 -1.6)
			(stroke
				(width 0.15)
				(type solid)
			)
			(layer "F.Fab")
		)
		(fp_line
			(start 2.101 -1.6)
			(end -2.1 -1.6)
			(stroke
				(width 0.15)
				(type solid)
			)
			(layer "F.Fab")
		)
		(fp_line
			(start 0.25 0.802)
			(end -0.248 0.802)
			(stroke
				(width 0.15)
				(type solid)
			)
			(layer "F.Fab")
		)
		(fp_line
			(start -0.248 -0.8)
			(end 0.25 -0.8)
			(stroke
				(width 0.15)
				(type solid)
			)
			(layer "F.Fab")
		)
		(fp_line
			(start -2.1 1.601)
			(end 2.101 1.601)
			(stroke
				(width 0.15)
				(type solid)
			)
			(layer "F.Fab")
		)
		(fp_line
			(start -2.1 -1.6)
			(end -2.1 1.601)
			(stroke
				(width 0.15)
				(type solid)
			)
			(layer "F.Fab")
		)
		(fp_arc
			(start 0.25 -0.8)
			(mid 1.051001 0.001)
			(end 0.25 0.802)
			(stroke
				(width 0.15)
				(type solid)
			)
			(layer "F.Fab")
		)
		(fp_arc
			(start -0.248 0.802)
			(mid -1.050001 0.001)
			(end -0.248 -0.8)
			(stroke
				(width 0.15)
				(type solid)
			)
			(layer "F.Fab")
		)
		(fp_text user "${REFERENCE}"
			(at -3 4.25 0)
			(layer "F.Fab")
			(effects
				(font
					(size 0.7 0.7)
					(thickness 0.15)
				)
				(justify right top)
			)
		)
		(fp_text user "License: Apache-2.0"
			(at -3 6.75 0)
			(layer "F.Fab")
			(effects
				(font
					(size 0.7 0.7)
					(thickness 0.15)
				)
				(justify right top)
			)
		)
		(fp_text user "Author: Antmicro"
			(at -3 5.5 0)
			(layer "F.Fab")
			(effects
				(font
					(size 0.7 0.7)
					(thickness 0.15)
				)
				(justify right top)
			)
		)
		(pad "1" smd rect
			(at -2.048 -0.8)
			(size 0.9 1)
			(layers "F.Cu" "F.Mask" "F.Paste")
			(net 495 "/SoM_Power/~{FORCE_RECOVERY}")
			(pinfunction "1")
			(pintype "passive")
		)
		(pad "2" smd rect
			(at 2.049999 -0.8)
			(size 0.9 1)
			(layers "F.Cu" "F.Mask" "F.Paste")
			(net 495 "/SoM_Power/~{FORCE_RECOVERY}")
			(pinfunction "2")
			(pintype "passive")
		)
		(pad "3" smd rect
			(at -2.048 0.802)
			(size 0.9 1)
			(layers "F.Cu" "F.Mask" "F.Paste")
			(net 1 "GND")
			(pinfunction "3")
			(pintype "passive")
		)
		(pad "4" smd rect
			(at 2.05 0.802001)
			(size 0.9 1)
			(layers "F.Cu" "F.Mask" "F.Paste")
			(net 1 "GND")
			(pinfunction "4")
			(pintype "passive")
		)
	)
	(footprint "antmicro-footprints:TP_SMD_0.75mm"
		(layer "F.Cu")
		(at 66.16 58.26 90)
		(property "Reference" "TP27"
			(at 1.56 -2.51 90)
			(layer "F.SilkS")
			(effects
				(font
					(size 0.7 0.7)
					(thickness 0.15)
				)
				(justify left bottom)
			)
		)
		(property "Value" "TP_0.75mm_SMD"
			(at 0 1.2 90)
			(layer "F.Fab")
			(effects
				(font
					(size 0.7 0.7)
					(thickness 0.15)
				)
				(justify left bottom)
			)
		)
		(property "Description" "SMT test point"
			(at 0 0 90)
			(layer "F.Fab")
			(hide yes)
			(effects
				(font
					(size 1.27 1.27)
					(thickness 0.15)
				)
			)
		)
		(property "MPN" ""
			(at 0 0 90)
			(unlocked yes)
			(layer "F.Fab")
			(hide yes)
			(effects
				(font
					(size 1 1)
					(thickness 0.15)
				)
			)
		)
		(property "Manufacturer" ""
			(at 0 0 90)
			(unlocked yes)
			(layer "F.Fab")
			(hide yes)
			(effects
				(font
					(size 1 1)
					(thickness 0.15)
				)
			)
		)
		(property "Author" "Antmicro"
			(at 0 0 90)
			(unlocked yes)
			(layer "F.Fab")
			(hide yes)
			(effects
				(font
					(size 1 1)
					(thickness 0.15)
				)
			)
		)
		(property "License" "Apache-2.0"
			(at 0 0 90)
			(unlocked yes)
			(layer "F.Fab")
			(hide yes)
			(effects
				(font
					(size 1 1)
					(thickness 0.15)
				)
			)
		)
		(sheetname "/CSI/")
		(sheetfile "csi.kicad_sch")
		(attr exclude_from_pos_files exclude_from_bom)
		(fp_circle
			(center 0 0)
			(end 0.475 0)
			(stroke
				(width 0.05)
				(type default)
			)
			(fill no)
			(layer "F.CrtYd")
		)
		(fp_text user "License: Apache-2.0"
			(at -0.4 5.101 90)
			(layer "F.Fab")
			(effects
				(font
					(size 0.7 0.7)
					(thickness 0.15)
				)
				(justify left bottom)
			)
		)
		(fp_text user "Author: Antmicro"
			(at -0.4 3.901 90)
			(layer "F.Fab")
			(effects
				(font
					(size 0.7 0.7)
					(thickness 0.15)
				)
				(justify left bottom)
			)
		)
		(fp_text user "${REFERENCE}"
			(at -0.4 2.7 90)
			(layer "F.Fab")
			(effects
				(font
					(size 0.7 0.7)
					(thickness 0.15)
				)
				(justify left bottom)
			)
		)
		(pad "1" smd circle
			(at 0 0 90)
			(size 0.75 0.75)
			(layers "F.Cu" "F.Mask")
			(net 1051 "/CSI/MUX_I2C_7_SDA")
			(pinfunction "1")
			(pintype "passive")
		)
	)
	(footprint "antmicro-footprints:C_0402_1005Metric"
		(layer "F.Cu")
		(at 178.2 67.42)
		(descr "Capacitor SMD 0402")
		(tags "capacitor SMD 0402")
		(property "Reference" "C281"
			(at -2.4 -0.62 0)
			(layer "F.SilkS")
			(effects
				(font
					(size 0.7 0.7)
					(thickness 0.15)
				)
				(justify left bottom)
			)
		)
		(property "Value" "C_100n_0402"
			(at -1.022927 2.155213 0)
			(layer "F.Fab")
			(effects
				(font
					(size 0.7 0.7)
					(thickness 0.15)
				)
				(justify left bottom)
			)
		)
		(property "Datasheet" "https://www.murata.com/products/productdetail?partno=GRM155R61H104KE14%23"
			(at 0 0 0)
			(layer "F.Fab")
			(hide yes)
			(effects
				(font
					(size 1.27 1.27)
					(thickness 0.15)
				)
			)
		)
		(property "Description" "SMD Multilayer Ceramic Capacitor, 0.1 µF, 50 V, 0402 [1005 Metric], ± 10%, X5R, GRM Series"
			(at 0 0 0)
			(layer "F.Fab")
			(hide yes)
			(effects
				(font
					(size 1.27 1.27)
					(thickness 0.15)
				)
			)
		)
		(property "Manufacturer" "Murata"
			(at 0 0 0)
			(unlocked yes)
			(layer "F.Fab")
			(hide yes)
			(effects
				(font
					(size 1 1)
					(thickness 0.15)
				)
			)
		)
		(property "MPN" "GRM155R61H104KE14D"
			(at 0 0 0)
			(unlocked yes)
			(layer "F.Fab")
			(hide yes)
			(effects
				(font
					(size 1 1)
					(thickness 0.15)
				)
			)
		)
		(property "Val" "100n"
			(at 0 0 0)
			(unlocked yes)
			(layer "F.Fab")
			(hide yes)
			(effects
				(font
					(size 1 1)
					(thickness 0.15)
				)
			)
		)
		(property "License" "Apache-2.0"
			(at 0 0 0)
			(unlocked yes)
			(layer "F.Fab")
			(hide yes)
			(effects
				(font
					(size 1 1)
					(thickness 0.15)
				)
			)
		)
		(property "Author" "Antmicro"
			(at 0 0 0)
			(unlocked yes)
			(layer "F.Fab")
			(hide yes)
			(effects
				(font
					(size 1 1)
					(thickness 0.15)
				)
			)
		)
		(property "Voltage" "50V"
			(at 0 0 0)
			(unlocked yes)
			(layer "F.Fab")
			(hide yes)
			(effects
				(font
					(size 1 1)
					(thickness 0.15)
				)
			)
		)
		(property "Dielectric" "X5R"
			(at 0 0 0)
			(unlocked yes)
			(layer "F.Fab")
			(hide yes)
			(effects
				(font
					(size 1 1)
					(thickness 0.15)
				)
			)
		)
		(component_classes
			(class "DCDC_20V")
		)
		(sheetname "/DCDC/")
		(sheetfile "dcdc.kicad_sch")
		(attr smd)
		(fp_rect
			(start -0.925 -0.47)
			(end 0.925 0.47)
			(stroke
				(width 0.05)
				(type default)
			)
			(fill no)
			(layer "F.CrtYd")
		)
		(fp_line
			(start -0.494 -0.25)
			(end 0.504 -0.25)
			(stroke
				(width 0.15)
				(type solid)
			)
			(layer "F.Fab")
		)
		(fp_line
			(start -0.494 0.248)
			(end -0.494 -0.25)
			(stroke
				(width 0.15)
				(type solid)
			)
			(layer "F.Fab")
		)
		(fp_line
			(start 0.504 -0.25)
			(end 0.504 0.248)
			(stroke
				(width 0.15)
				(type solid)
			)
			(layer "F.Fab")
		)
		(fp_line
			(start 0.504 0.248)
			(end -0.494 0.248)
			(stroke
				(width 0.15)
				(type solid)
			)
			(layer "F.Fab")
		)
		(fp_text user "Author: Antmicro"
			(at -0.939 3.399 0)
			(layer "F.Fab")
			(effects
				(font
					(size 0.7 0.7)
					(thickness 0.15)
				)
				(justify left bottom)
			)
		)
		(fp_text user "License: Apache-2.0"
			(at -0.939 5.799 0)
			(layer "F.Fab")
			(effects
				(font
					(size 0.7 0.7)
					(thickness 0.15)
				)
				(justify left bottom)
			)
		)
		(fp_text user "${REFERENCE}"
			(at -0.939 4.599 0)
			(layer "F.Fab")
			(effects
				(font
					(size 0.7 0.7)
					(thickness 0.15)
				)
				(justify left bottom)
			)
		)
		(pad "1" smd roundrect
			(at -0.48 0)
			(size 0.59 0.64)
			(layers "F.Cu" "F.Mask" "F.Paste")
			(roundrect_rratio 0.25)
			(net 1104 "/DCDC/20V_PHASE")
			(pintype "passive")
		)
		(pad "2" smd roundrect
			(at 0.48 0)
			(size 0.59 0.64)
			(layers "F.Cu" "F.Mask" "F.Paste")
			(roundrect_rratio 0.25)
			(net 1086 "/DCDC/20V_BOOT")
			(pintype "passive")
		)
	)
)
